(kicad_pcb
	(version 20260206)
	(generator "pcbnew")
	(generator_version "10.0")
	(general
		(thickness 1.6)
		(legacy_teardrops no)
	)
	(paper "A4")
	(title_block
		(title "04192023_DAF0TMB3IC0_F0TG_MB_C_brd_V02_OCP.brd")
		(comment 1 "Grand Teton / footprints 2327-2333 of 8354")
	)
	(layers
		(0 "F.Cu" signal "TOP")
		(4 "In1.Cu" signal "GND")
		(6 "In2.Cu" signal "IN1")
		(8 "In3.Cu" signal "GND1")
		(10 "In4.Cu" signal "IN2")
		(12 "In5.Cu" signal "GND2")
		(14 "In6.Cu" signal "IN3")
		(16 "In7.Cu" signal "GND3")
		(18 "In8.Cu" signal "VCC")
		(20 "In9.Cu" signal "VCC1")
		(22 "In10.Cu" signal "GND4")
		(24 "In11.Cu" signal "IN4")
		(26 "In12.Cu" signal "GND5")
		(28 "In13.Cu" signal "IN5")
		(30 "In14.Cu" signal "GND6")
		(32 "In15.Cu" signal "IN6")
		(34 "In16.Cu" signal "GND7")
		(2 "B.Cu" signal "BOTTOM")
		(9 "F.Adhes" user "F.Adhesive")
		(11 "B.Adhes" user "B.Adhesive")
		(13 "F.Paste" user "Package Geometry/Pastemask Top")
		(15 "B.Paste" user "Package Geometry/Pastemask Bottom")
		(5 "F.SilkS" user "Ref Des/Silkscreen Top")
		(7 "B.SilkS" user "Ref Des/Silkscreen Bottom")
		(1 "F.Mask" user "Board Geometry/Soldermask Top")
		(3 "B.Mask" user "Board Geometry/Soldermask Bottom")
		(17 "Dwgs.User" user "User.Drawings")
		(19 "Cmts.User" user "User.Comments")
		(21 "Eco1.User" user "User.Eco1")
		(23 "Eco2.User" user "User.Eco2")
		(25 "Edge.Cuts" user "Board Geometry/Outline")
		(27 "Margin" user)
		(31 "F.CrtYd" user "Package Geometry/Place Bound Top")
		(29 "B.CrtYd" user "Package Geometry/Place Bound Bottom")
		(35 "F.Fab" user "Ref Des/Assembly Top")
		(33 "B.Fab" user "Ref Des/Assembly Bottom")
	)
	(footprint ""
		(layer "F.Cu")
		(at 329.360022 -34.985706 180)
		(property "Reference" "R1793"
			(at 0 0 180)
			(layer "F.SilkS")
			(hide yes)
			(effects
				(font
					(size 1.27 1.27)
				)
			)
		)
		(property "Value" ""
			(at 0 0 180)
			(layer "F.Fab")
			(effects
				(font
					(size 1.27 1.27)
				)
			)
		)
		(duplicate_pad_numbers_are_jumpers no)
		(fp_line
			(start 0.7874 0.4064)
			(end -0.7874 0.4064)
			(stroke
				(width 0.1524)
				(type default)
			)
			(layer "F.SilkS")
		)
		(fp_line
			(start 0.7874 -0.4064)
			(end 0.7874 0.4064)
			(stroke
				(width 0.1524)
				(type default)
			)
			(layer "F.SilkS")
		)
		(fp_line
			(start -0.7874 0.4064)
			(end -0.7874 -0.4064)
			(stroke
				(width 0.1524)
				(type default)
			)
			(layer "F.SilkS")
		)
		(fp_line
			(start -0.7874 -0.4064)
			(end 0.7874 -0.4064)
			(stroke
				(width 0.1524)
				(type default)
			)
			(layer "F.SilkS")
		)
		(fp_line
			(start 0.67945 0.3048)
			(end 0.120396 0.3048)
			(stroke
				(width 0.1)
				(type default)
			)
			(layer "F.Fab")
		)
		(fp_line
			(start 0.67945 -0.3048)
			(end 0.67945 0.3048)
			(stroke
				(width 0.1)
				(type default)
			)
			(layer "F.Fab")
		)
		(fp_line
			(start 0.12065 -0.2794)
			(end 0.12065 -0.3048)
			(stroke
				(width 0.1)
				(type default)
			)
			(layer "F.Fab")
		)
		(fp_line
			(start 0.12065 -0.3048)
			(end 0.67945 -0.3048)
			(stroke
				(width 0.1)
				(type default)
			)
			(layer "F.Fab")
		)
		(fp_line
			(start 0.120396 0.3048)
			(end 0.120396 0.2794)
			(stroke
				(width 0.1)
				(type default)
			)
			(layer "F.Fab")
		)
		(fp_line
			(start 0.120396 0.2794)
			(end -0.12065 0.2794)
			(stroke
				(width 0.1)
				(type default)
			)
			(layer "F.Fab")
		)
		(fp_line
			(start -0.12065 0.3048)
			(end -0.67945 0.3048)
			(stroke
				(width 0.1)
				(type default)
			)
			(layer "F.Fab")
		)
		(fp_line
			(start -0.12065 0.2794)
			(end -0.12065 0.3048)
			(stroke
				(width 0.1)
				(type default)
			)
			(layer "F.Fab")
		)
		(fp_line
			(start -0.12065 -0.2794)
			(end 0.12065 -0.2794)
			(stroke
				(width 0.1)
				(type default)
			)
			(layer "F.Fab")
		)
		(fp_line
			(start -0.12065 -0.305054)
			(end -0.12065 -0.2794)
			(stroke
				(width 0.1)
				(type default)
			)
			(layer "F.Fab")
		)
		(fp_line
			(start -0.67945 0.3048)
			(end -0.67945 -0.305054)
			(stroke
				(width 0.1)
				(type default)
			)
			(layer "F.Fab")
		)
		(fp_line
			(start -0.67945 -0.305054)
			(end -0.12065 -0.305054)
			(stroke
				(width 0.1)
				(type default)
			)
			(layer "F.Fab")
		)
		(pad "1" smd circle
			(at -0.40005 0 180)
			(size 0 0)
			(layers "F.Cu" "F.Mask" "F.Paste")
			(net "SMB_SCM_2_R4_SCL")
		)
		(pad "2" smd circle
			(at 0.40005 0 180)
			(size 0 0)
			(layers "F.Cu" "F.Mask" "F.Paste")
			(net "SMB_SEN_MAM_3V3AUX_SCL")
		)
	)
	(footprint ""
		(layer "F.Cu")
		(at 50.256694 -16.099536 90)
		(property "Reference" "C703"
			(at 0 0 90)
			(layer "F.SilkS")
			(hide yes)
			(effects
				(font
					(size 1.27 1.27)
				)
			)
		)
		(property "Value" ""
			(at 0 0 90)
			(layer "F.Fab")
			(effects
				(font
					(size 1.27 1.27)
				)
			)
		)
		(duplicate_pad_numbers_are_jumpers no)
		(fp_line
			(start 0.299974 -0.150114)
			(end 0.299974 0.150114)
			(stroke
				(width 0.1)
				(type default)
			)
			(layer "F.Fab")
		)
		(fp_line
			(start -0.299974 -0.150114)
			(end 0.299974 -0.150114)
			(stroke
				(width 0.1)
				(type default)
			)
			(layer "F.Fab")
		)
		(fp_line
			(start 0.299974 0.150114)
			(end -0.299974 0.150114)
			(stroke
				(width 0.1)
				(type default)
			)
			(layer "F.Fab")
		)
		(fp_line
			(start -0.299974 0.150114)
			(end -0.299974 -0.150114)
			(stroke
				(width 0.1)
				(type default)
			)
			(layer "F.Fab")
		)
		(pad "1" smd rect
			(at -0.2667 0 90)
			(size 0.3048 0.381)
			(layers "F.Cu" "F.Mask" "F.Paste")
			(net "P5E_CPU1_G1_TX_C_DP<3>")
		)
		(pad "2" smd rect
			(at 0.2667 0 90)
			(size 0.3048 0.381)
			(layers "F.Cu" "F.Mask" "F.Paste")
			(net "P5E_CPU1_G1_TX_DP<3>")
		)
	)
	(footprint ""
		(layer "F.Cu")
		(at 191.41694 -402.341842)
		(property "Reference" "R2588"
			(at 0 0 0)
			(layer "F.SilkS")
			(hide yes)
			(effects
				(font
					(size 1.27 1.27)
				)
			)
		)
		(property "Value" ""
			(at 0 0 0)
			(layer "F.Fab")
			(effects
				(font
					(size 1.27 1.27)
				)
			)
		)
		(duplicate_pad_numbers_are_jumpers no)
		(fp_line
			(start -0.7874 -0.4064)
			(end 0.7874 -0.4064)
			(stroke
				(width 0.1524)
				(type default)
			)
			(layer "F.SilkS")
		)
		(fp_line
			(start -0.7874 0.4064)
			(end -0.7874 -0.4064)
			(stroke
				(width 0.1524)
				(type default)
			)
			(layer "F.SilkS")
		)
		(fp_line
			(start 0.7874 -0.4064)
			(end 0.7874 0.4064)
			(stroke
				(width 0.1524)
				(type default)
			)
			(layer "F.SilkS")
		)
		(fp_line
			(start 0.7874 0.4064)
			(end -0.7874 0.4064)
			(stroke
				(width 0.1524)
				(type default)
			)
			(layer "F.SilkS")
		)
		(fp_line
			(start -0.67945 -0.305054)
			(end -0.12065 -0.305054)
			(stroke
				(width 0.1)
				(type default)
			)
			(layer "F.Fab")
		)
		(fp_line
			(start -0.67945 0.3048)
			(end -0.67945 -0.305054)
			(stroke
				(width 0.1)
				(type default)
			)
			(layer "F.Fab")
		)
		(fp_line
			(start -0.12065 -0.305054)
			(end -0.12065 -0.2794)
			(stroke
				(width 0.1)
				(type default)
			)
			(layer "F.Fab")
		)
		(fp_line
			(start -0.12065 -0.2794)
			(end 0.12065 -0.2794)
			(stroke
				(width 0.1)
				(type default)
			)
			(layer "F.Fab")
		)
		(fp_line
			(start -0.12065 0.2794)
			(end -0.12065 0.3048)
			(stroke
				(width 0.1)
				(type default)
			)
			(layer "F.Fab")
		)
		(fp_line
			(start -0.12065 0.3048)
			(end -0.67945 0.3048)
			(stroke
				(width 0.1)
				(type default)
			)
			(layer "F.Fab")
		)
		(fp_line
			(start 0.120396 0.2794)
			(end -0.12065 0.2794)
			(stroke
				(width 0.1)
				(type default)
			)
			(layer "F.Fab")
		)
		(fp_line
			(start 0.120396 0.3048)
			(end 0.120396 0.2794)
			(stroke
				(width 0.1)
				(type default)
			)
			(layer "F.Fab")
		)
		(fp_line
			(start 0.12065 -0.3048)
			(end 0.67945 -0.3048)
			(stroke
				(width 0.1)
				(type default)
			)
			(layer "F.Fab")
		)
		(fp_line
			(start 0.12065 -0.2794)
			(end 0.12065 -0.3048)
			(stroke
				(width 0.1)
				(type default)
			)
			(layer "F.Fab")
		)
		(fp_line
			(start 0.67945 -0.3048)
			(end 0.67945 0.3048)
			(stroke
				(width 0.1)
				(type default)
			)
			(layer "F.Fab")
		)
		(fp_line
			(start 0.67945 0.3048)
			(end 0.120396 0.3048)
			(stroke
				(width 0.1)
				(type default)
			)
			(layer "F.Fab")
		)
		(pad "1" smd circle
			(at -0.40005 0)
			(size 0 0)
			(layers "F.Cu" "F.Mask" "F.Paste")
			(net "HSC_FAULT")
		)
		(pad "2" smd circle
			(at 0.40005 0)
			(size 0 0)
			(layers "F.Cu" "F.Mask" "F.Paste")
			(net "IRQ_HSC_FAULT_N")
		)
	)
	(footprint ""
		(layer "F.Cu")
		(at 185.039 -129.377948 90)
		(property "Reference" "R933"
			(at 0 0 90)
			(layer "F.SilkS")
			(hide yes)
			(effects
				(font
					(size 1.27 1.27)
				)
			)
		)
		(property "Value" ""
			(at 0 0 90)
			(layer "F.Fab")
			(effects
				(font
					(size 1.27 1.27)
				)
			)
		)
		(duplicate_pad_numbers_are_jumpers no)
		(fp_line
			(start 0.7874 -0.4064)
			(end 0.7874 0.4064)
			(stroke
				(width 0.1524)
				(type default)
			)
			(layer "F.SilkS")
		)
		(fp_line
			(start -0.7874 -0.4064)
			(end 0.7874 -0.4064)
			(stroke
				(width 0.1524)
				(type default)
			)
			(layer "F.SilkS")
		)
		(fp_line
			(start 0.7874 0.4064)
			(end -0.7874 0.4064)
			(stroke
				(width 0.1524)
				(type default)
			)
			(layer "F.SilkS")
		)
		(fp_line
			(start -0.7874 0.4064)
			(end -0.7874 -0.4064)
			(stroke
				(width 0.1524)
				(type default)
			)
			(layer "F.SilkS")
		)
		(fp_line
			(start -0.12065 -0.305054)
			(end -0.12065 -0.2794)
			(stroke
				(width 0.1)
				(type default)
			)
			(layer "F.Fab")
		)
		(fp_line
			(start -0.67945 -0.305054)
			(end -0.12065 -0.305054)
			(stroke
				(width 0.1)
				(type default)
			)
			(layer "F.Fab")
		)
		(fp_line
			(start 0.67945 -0.3048)
			(end 0.67945 0.3048)
			(stroke
				(width 0.1)
				(type default)
			)
			(layer "F.Fab")
		)
		(fp_line
			(start 0.12065 -0.3048)
			(end 0.67945 -0.3048)
			(stroke
				(width 0.1)
				(type default)
			)
			(layer "F.Fab")
		)
		(fp_line
			(start 0.12065 -0.2794)
			(end 0.12065 -0.3048)
			(stroke
				(width 0.1)
				(type default)
			)
			(layer "F.Fab")
		)
		(fp_line
			(start -0.12065 -0.2794)
			(end 0.12065 -0.2794)
			(stroke
				(width 0.1)
				(type default)
			)
			(layer "F.Fab")
		)
		(fp_line
			(start 0.120396 0.2794)
			(end -0.12065 0.2794)
			(stroke
				(width 0.1)
				(type default)
			)
			(layer "F.Fab")
		)
		(fp_line
			(start -0.12065 0.2794)
			(end -0.12065 0.3048)
			(stroke
				(width 0.1)
				(type default)
			)
			(layer "F.Fab")
		)
		(fp_line
			(start 0.67945 0.3048)
			(end 0.120396 0.3048)
			(stroke
				(width 0.1)
				(type default)
			)
			(layer "F.Fab")
		)
		(fp_line
			(start 0.120396 0.3048)
			(end 0.120396 0.2794)
			(stroke
				(width 0.1)
				(type default)
			)
			(layer "F.Fab")
		)
		(fp_line
			(start -0.12065 0.3048)
			(end -0.67945 0.3048)
			(stroke
				(width 0.1)
				(type default)
			)
			(layer "F.Fab")
		)
		(fp_line
			(start -0.67945 0.3048)
			(end -0.67945 -0.305054)
			(stroke
				(width 0.1)
				(type default)
			)
			(layer "F.Fab")
		)
		(pad "1" smd circle
			(at -0.40005 0 90)
			(size 0 0)
			(layers "F.Cu" "F.Mask" "F.Paste")
			(net "FM_SMERR_LED_R_N")
		)
		(pad "2" smd circle
			(at 0.40005 0 90)
			(size 0 0)
			(layers "F.Cu" "F.Mask" "F.Paste")
			(net "FM_SMERR_LED_N")
		)
	)
	(footprint ""
		(layer "F.Cu")
		(at 41.050718 -351.10547)
		(property "Reference" "PC439_2"
			(at 0 0 0)
			(layer "F.SilkS")
			(hide yes)
			(effects
				(font
					(size 1.27 1.27)
				)
			)
		)
		(property "Value" ""
			(at 0 0 0)
			(layer "F.Fab")
			(effects
				(font
					(size 1.27 1.27)
				)
			)
		)
		(duplicate_pad_numbers_are_jumpers no)
		(fp_line
			(start -0.7874 -0.4064)
			(end 0.7874 -0.4064)
			(stroke
				(width 0.1524)
				(type default)
			)
			(layer "F.SilkS")
		)
		(fp_line
			(start -0.7874 0.4064)
			(end -0.7874 -0.4064)
			(stroke
				(width 0.1524)
				(type default)
			)
			(layer "F.SilkS")
		)
		(fp_line
			(start 0.7874 -0.4064)
			(end 0.7874 0.4064)
			(stroke
				(width 0.1524)
				(type default)
			)
			(layer "F.SilkS")
		)
		(fp_line
			(start 0.7874 0.4064)
			(end -0.7874 0.4064)
			(stroke
				(width 0.1524)
				(type default)
			)
			(layer "F.SilkS")
		)
		(fp_line
			(start -0.67945 -0.305054)
			(end -0.12065 -0.305054)
			(stroke
				(width 0.1)
				(type default)
			)
			(layer "F.Fab")
		)
		(fp_line
			(start -0.67945 0.3048)
			(end -0.67945 -0.305054)
			(stroke
				(width 0.1)
				(type default)
			)
			(layer "F.Fab")
		)
		(fp_line
			(start -0.12065 -0.305054)
			(end -0.12065 -0.2794)
			(stroke
				(width 0.1)
				(type default)
			)
			(layer "F.Fab")
		)
		(fp_line
			(start -0.12065 -0.2794)
			(end 0.12065 -0.2794)
			(stroke
				(width 0.1)
				(type default)
			)
			(layer "F.Fab")
		)
		(fp_line
			(start -0.12065 0.2794)
			(end -0.12065 0.3048)
			(stroke
				(width 0.1)
				(type default)
			)
			(layer "F.Fab")
		)
		(fp_line
			(start -0.12065 0.3048)
			(end -0.67945 0.3048)
			(stroke
				(width 0.1)
				(type default)
			)
			(layer "F.Fab")
		)
		(fp_line
			(start 0.120396 0.2794)
			(end -0.12065 0.2794)
			(stroke
				(width 0.1)
				(type default)
			)
			(layer "F.Fab")
		)
		(fp_line
			(start 0.120396 0.3048)
			(end 0.120396 0.2794)
			(stroke
				(width 0.1)
				(type default)
			)
			(layer "F.Fab")
		)
		(fp_line
			(start 0.12065 -0.3048)
			(end 0.67945 -0.3048)
			(stroke
				(width 0.1)
				(type default)
			)
			(layer "F.Fab")
		)
		(fp_line
			(start 0.12065 -0.2794)
			(end 0.12065 -0.3048)
			(stroke
				(width 0.1)
				(type default)
			)
			(layer "F.Fab")
		)
		(fp_line
			(start 0.67945 -0.3048)
			(end 0.67945 0.3048)
			(stroke
				(width 0.1)
				(type default)
			)
			(layer "F.Fab")
		)
		(fp_line
			(start 0.67945 0.3048)
			(end 0.120396 0.3048)
			(stroke
				(width 0.1)
				(type default)
			)
			(layer "F.Fab")
		)
		(pad "1" smd circle
			(at -0.40005 0)
			(size 0 0)
			(layers "F.Cu" "F.Mask" "F.Paste")
			(net "SW_P12V_AUX_PVDDIO_P1_FLT")
		)
		(pad "2" smd circle
			(at 0.40005 0)
			(size 0 0)
			(layers "F.Cu" "F.Mask" "F.Paste")
			(net "GND")
		)
	)
	(footprint ""
		(layer "F.Cu")
		(at 10.066782 -413.231584)
		(property "Reference" "R663"
			(at 0 0 0)
			(layer "F.SilkS")
			(hide yes)
			(effects
				(font
					(size 1.27 1.27)
				)
			)
		)
		(property "Value" ""
			(at 0 0 0)
			(layer "F.Fab")
			(effects
				(font
					(size 1.27 1.27)
				)
			)
		)
		(duplicate_pad_numbers_are_jumpers no)
		(fp_line
			(start -0.7874 -0.4064)
			(end 0.7874 -0.4064)
			(stroke
				(width 0.1524)
				(type default)
			)
			(layer "F.SilkS")
		)
		(fp_line
			(start -0.7874 0.4064)
			(end -0.7874 -0.4064)
			(stroke
				(width 0.1524)
				(type default)
			)
			(layer "F.SilkS")
		)
		(fp_line
			(start 0.7874 -0.4064)
			(end 0.7874 0.4064)
			(stroke
				(width 0.1524)
				(type default)
			)
			(layer "F.SilkS")
		)
		(fp_line
			(start 0.7874 0.4064)
			(end -0.7874 0.4064)
			(stroke
				(width 0.1524)
				(type default)
			)
			(layer "F.SilkS")
		)
		(fp_line
			(start -0.67945 -0.305054)
			(end -0.12065 -0.305054)
			(stroke
				(width 0.1)
				(type default)
			)
			(layer "F.Fab")
		)
		(fp_line
			(start -0.67945 0.3048)
			(end -0.67945 -0.305054)
			(stroke
				(width 0.1)
				(type default)
			)
			(layer "F.Fab")
		)
		(fp_line
			(start -0.12065 -0.305054)
			(end -0.12065 -0.2794)
			(stroke
				(width 0.1)
				(type default)
			)
			(layer "F.Fab")
		)
		(fp_line
			(start -0.12065 -0.2794)
			(end 0.12065 -0.2794)
			(stroke
				(width 0.1)
				(type default)
			)
			(layer "F.Fab")
		)
		(fp_line
			(start -0.12065 0.2794)
			(end -0.12065 0.3048)
			(stroke
				(width 0.1)
				(type default)
			)
			(layer "F.Fab")
		)
		(fp_line
			(start -0.12065 0.3048)
			(end -0.67945 0.3048)
			(stroke
				(width 0.1)
				(type default)
			)
			(layer "F.Fab")
		)
		(fp_line
			(start 0.120396 0.2794)
			(end -0.12065 0.2794)
			(stroke
				(width 0.1)
				(type default)
			)
			(layer "F.Fab")
		)
		(fp_line
			(start 0.120396 0.3048)
			(end 0.120396 0.2794)
			(stroke
				(width 0.1)
				(type default)
			)
			(layer "F.Fab")
		)
		(fp_line
			(start 0.12065 -0.3048)
			(end 0.67945 -0.3048)
			(stroke
				(width 0.1)
				(type default)
			)
			(layer "F.Fab")
		)
		(fp_line
			(start 0.12065 -0.2794)
			(end 0.12065 -0.3048)
			(stroke
				(width 0.1)
				(type default)
			)
			(layer "F.Fab")
		)
		(fp_line
			(start 0.67945 -0.3048)
			(end 0.67945 0.3048)
			(stroke
				(width 0.1)
				(type default)
			)
			(layer "F.Fab")
		)
		(fp_line
			(start 0.67945 0.3048)
			(end 0.120396 0.3048)
			(stroke
				(width 0.1)
				(type default)
			)
			(layer "F.Fab")
		)
		(pad "1" smd circle
			(at -0.40005 0)
			(size 0 0)
			(layers "F.Cu" "F.Mask" "F.Paste")
			(net "P3V3_AUX")
		)
		(pad "2" smd circle
			(at 0.40005 0)
			(size 0 0)
			(layers "F.Cu" "F.Mask" "F.Paste")
			(net "P0V9_RETIMER_CPU1_CFP")
		)
	)
	(footprint ""
		(layer "F.Cu")
		(at 200.952608 -117.689376)
		(property "Reference" "R4148"
			(at 0 0 0)
			(layer "F.SilkS")
			(hide yes)
			(effects
				(font
					(size 1.27 1.27)
				)
			)
		)
		(property "Value" ""
			(at 0 0 0)
			(layer "F.Fab")
			(effects
				(font
					(size 1.27 1.27)
				)
			)
		)
		(duplicate_pad_numbers_are_jumpers no)
		(fp_line
			(start -0.7874 -0.4064)
			(end 0.7874 -0.4064)
			(stroke
				(width 0.1524)
				(type default)
			)
			(layer "F.SilkS")
		)
		(fp_line
			(start -0.7874 0.4064)
			(end -0.7874 -0.4064)
			(stroke
				(width 0.1524)
				(type default)
			)
			(layer "F.SilkS")
		)
		(fp_line
			(start 0.7874 -0.4064)
			(end 0.7874 0.4064)
			(stroke
				(width 0.1524)
				(type default)
			)
			(layer "F.SilkS")
		)
		(fp_line
			(start 0.7874 0.4064)
			(end -0.7874 0.4064)
			(stroke
				(width 0.1524)
				(type default)
			)
			(layer "F.SilkS")
		)
		(fp_line
			(start -0.67945 -0.305054)
			(end -0.12065 -0.305054)
			(stroke
				(width 0.1)
				(type default)
			)
			(layer "F.Fab")
		)
		(fp_line
			(start -0.67945 0.3048)
			(end -0.67945 -0.305054)
			(stroke
				(width 0.1)
				(type default)
			)
			(layer "F.Fab")
		)
		(fp_line
			(start -0.12065 -0.305054)
			(end -0.12065 -0.2794)
			(stroke
				(width 0.1)
				(type default)
			)
			(layer "F.Fab")
		)
		(fp_line
			(start -0.12065 -0.2794)
			(end 0.12065 -0.2794)
			(stroke
				(width 0.1)
				(type default)
			)
			(layer "F.Fab")
		)
		(fp_line
			(start -0.12065 0.2794)
			(end -0.12065 0.3048)
			(stroke
				(width 0.1)
				(type default)
			)
			(layer "F.Fab")
		)
		(fp_line
			(start -0.12065 0.3048)
			(end -0.67945 0.3048)
			(stroke
				(width 0.1)
				(type default)
			)
			(layer "F.Fab")
		)
		(fp_line
			(start 0.120396 0.2794)
			(end -0.12065 0.2794)
			(stroke
				(width 0.1)
				(type default)
			)
			(layer "F.Fab")
		)
		(fp_line
			(start 0.120396 0.3048)
			(end 0.120396 0.2794)
			(stroke
				(width 0.1)
				(type default)
			)
			(layer "F.Fab")
		)
		(fp_line
			(start 0.12065 -0.3048)
			(end 0.67945 -0.3048)
			(stroke
				(width 0.1)
				(type default)
			)
			(layer "F.Fab")
		)
		(fp_line
			(start 0.12065 -0.2794)
			(end 0.12065 -0.3048)
			(stroke
				(width 0.1)
				(type default)
			)
			(layer "F.Fab")
		)
		(fp_line
			(start 0.67945 -0.3048)
			(end 0.67945 0.3048)
			(stroke
				(width 0.1)
				(type default)
			)
			(layer "F.Fab")
		)
		(fp_line
			(start 0.67945 0.3048)
			(end 0.120396 0.3048)
			(stroke
				(width 0.1)
				(type default)
			)
			(layer "F.Fab")
		)
		(pad "1" smd circle
			(at -0.40005 0)
			(size 0 0)
			(layers "F.Cu" "F.Mask" "F.Paste")
			(net "GPU_3V3IO_RSVD5_FFU_ISO_R")
		)
		(pad "2" smd circle
			(at 0.40005 0)
			(size 0 0)
			(layers "F.Cu" "F.Mask" "F.Paste")
			(net "GPU_3V3IO_RSVD5_FFU_ISO")
		)
	)
)
